(kicad_pcb
	(version 20241229)
	(generator "pcbnew")
	(generator_version "9.0")
	(general
		(thickness 1.599998)
		(legacy_teardrops no)
	)
	(paper "A4")
	(title_block
		(date "2023-02-12")
		(rev "1.1.5")
		(comment 9 "footprints 239-244 of 473")
	)
	(layers
		(0 "F.Cu" signal)
		(4 "In1.Cu" power "In1.GND")
		(6 "In2.Cu" signal)
		(8 "In3.Cu" power "In3.GND")
		(10 "In4.Cu" power "In4.VCC")
		(12 "In5.Cu" signal)
		(14 "In6.Cu" power "In6.VCC")
		(2 "B.Cu" signal)
		(9 "F.Adhes" user "F.Adhesive")
		(11 "B.Adhes" user "B.Adhesive")
		(13 "F.Paste" user)
		(15 "B.Paste" user)
		(5 "F.SilkS" user "F.Silkscreen")
		(7 "B.SilkS" user "B.Silkscreen")
		(1 "F.Mask" user)
		(3 "B.Mask" user)
		(17 "Dwgs.User" user "User.Drawings")
		(19 "Cmts.User" user "User.Comments")
		(21 "Eco1.User" user "User.Eco1")
		(23 "Eco2.User" user "User.Eco2")
		(25 "Edge.Cuts" user)
		(27 "Margin" user)
		(31 "F.CrtYd" user "F.Courtyard")
		(29 "B.CrtYd" user "B.Courtyard")
		(35 "F.Fab" user)
		(33 "B.Fab" user)
	)
	(footprint "antmicro-footprints:LED_0603_1608Metric_G"
		(layer "F.Cu")
		(at 137.7825 84.699)
		(descr "LED SMD 0603 Green")
		(tags "LED SMD 0603 Green")
		(property "Reference" "PWR5"
			(at -4.6825 -0.799 0)
			(layer "F.SilkS")
			(effects
				(font
					(size 0.7 0.7)
					(thickness 0.15)
				)
				(justify left bottom)
			)
		)
		(property "Value" "LED_G_0603_KP-1608CGCK"
			(at 0 1.6 0)
			(layer "F.Fab")
			(effects
				(font
					(size 0.7 0.7)
					(thickness 0.15)
				)
				(justify left bottom)
			)
		)
		(property "Author" "Antmicro"
			(at 0 0 0)
			(layer "F.Fab")
			(hide yes)
			(effects
				(font
					(size 1 1)
					(thickness 0.15)
				)
			)
		)
		(property "License" "Apache-2.0"
			(at 0 0 0)
			(layer "F.Fab")
			(hide yes)
			(effects
				(font
					(size 1 1)
					(thickness 0.15)
				)
			)
		)
		(property "MPN" "KP-1608CGCK"
			(at 0 0 0)
			(layer "F.Fab")
			(hide yes)
			(effects
				(font
					(size 1 1)
					(thickness 0.15)
				)
			)
		)
		(property "Manufacturer" "Kingbright"
			(at 0 0 0)
			(layer "F.Fab")
			(hide yes)
			(effects
				(font
					(size 1 1)
					(thickness 0.15)
				)
			)
		)
		(sheetname "Supply")
		(sheetfile "supply.kicad_sch")
		(attr smd)
		(fp_line
			(start -0.27 -0.35)
			(end 0.27 -0.35)
			(stroke
				(width 0.15)
				(type solid)
			)
			(layer "F.SilkS")
		)
		(fp_line
			(start -0.27 0.351)
			(end 0.27 0.351)
			(stroke
				(width 0.15)
				(type solid)
			)
			(layer "F.SilkS")
		)
		(fp_line
			(start -0.106328 -0.200008)
			(end -0.106328 0.199992)
			(stroke
				(width 0.1)
				(type solid)
			)
			(layer "F.SilkS")
		)
		(fp_line
			(start -0.106328 -0.200008)
			(end 0.093672 -8e-06)
			(stroke
				(width 0.1)
				(type solid)
			)
			(layer "F.SilkS")
		)
		(fp_line
			(start -0.106328 -8e-06)
			(end -0.29 0)
			(stroke
				(width 0.1)
				(type solid)
			)
			(layer "F.SilkS")
		)
		(fp_line
			(start 0.093672 -0.200008)
			(end 0.093672 0.199992)
			(stroke
				(width 0.1)
				(type solid)
			)
			(layer "F.SilkS")
		)
		(fp_line
			(start 0.093672 -8e-06)
			(end -0.106328 0.199992)
			(stroke
				(width 0.1)
				(type solid)
			)
			(layer "F.SilkS")
		)
		(fp_line
			(start 0.093672 -8e-06)
			(end 0.293672 -8e-06)
			(stroke
				(width 0.1)
				(type solid)
			)
			(layer "F.SilkS")
		)
		(fp_line
			(start 1.25 0.32)
			(end 1.25 -0.32)
			(stroke
				(width 0.15)
				(type solid)
			)
			(layer "F.SilkS")
		)
		(fp_rect
			(start 1.26 0.65)
			(end -1.26 -0.65)
			(stroke
				(width 0.05)
				(type solid)
			)
			(fill no)
			(layer "F.CrtYd")
		)
		(fp_line
			(start -0.599 0)
			(end -0.201 0)
			(stroke
				(width 0.15)
				(type solid)
			)
			(layer "F.Fab")
		)
		(fp_line
			(start -0.201 -0.2)
			(end -0.201 0)
			(stroke
				(width 0.15)
				(type solid)
			)
			(layer "F.Fab")
		)
		(fp_line
			(start -0.201 0)
			(end -0.201 0.202)
			(stroke
				(width 0.15)
				(type solid)
			)
			(layer "F.Fab")
		)
		(fp_line
			(start -0.201 0.202)
			(end 0.101 0)
			(stroke
				(width 0.15)
				(type solid)
			)
			(layer "F.Fab")
		)
		(fp_line
			(start 0.101 0)
			(end -0.201 -0.2)
			(stroke
				(width 0.15)
				(type solid)
			)
			(layer "F.Fab")
		)
		(fp_line
			(start 0.199 -0.2)
			(end 0.199 -0.1)
			(stroke
				(width 0.15)
				(type solid)
			)
			(layer "F.Fab")
		)
		(fp_line
			(start 0.199 0)
			(end 0.597 0)
			(stroke
				(width 0.15)
				(type solid)
			)
			(layer "F.Fab")
		)
		(fp_line
			(start 0.199 0.202)
			(end 0.199 -0.1)
			(stroke
				(width 0.15)
				(type solid)
			)
			(layer "F.Fab")
		)
		(fp_rect
			(start -0.848 -0.4)
			(end 0.85 0.402)
			(stroke
				(width 0.15)
				(type solid)
			)
			(fill no)
			(layer "F.Fab")
		)
		(pad "1" smd rect
			(at -0.75 0 180)
			(size 0.8 0.8)
			(layers "F.Cu" "F.Mask" "F.Paste")
			(net 459 "3V3_SYS")
			(pinfunction "1")
			(pintype "passive")
		)
		(pad "2" smd rect
			(at 0.75 0 180)
			(size 0.8 0.8)
			(layers "F.Cu" "F.Mask" "F.Paste")
			(net 557 "Net-(PWR5-Pad2)")
			(pinfunction "2")
			(pintype "passive")
		)
	)
	(footprint "antmicro-footprints:C_0402_1005Metric"
		(layer "F.Cu")
		(at 123.4325 96.249 180)
		(descr "Capacitor SMD 0402")
		(tags "capacitor SMD 0402")
		(property "Reference" "C176"
			(at 1.9325 2.449 180)
			(layer "F.SilkS")
			(effects
				(font
					(size 0.7 0.7)
					(thickness 0.15)
				)
				(justify left bottom)
			)
		)
		(property "Value" "C_22u_0402"
			(at 0 1.4 180)
			(layer "F.Fab")
			(effects
				(font
					(size 0.7 0.7)
					(thickness 0.15)
				)
				(justify left bottom)
			)
		)
		(property "Description" " "
			(at 0 0 180)
			(layer "F.Fab")
			(hide yes)
			(effects
				(font
					(size 1.27 1.27)
					(thickness 0.15)
				)
			)
		)
		(property "Author" "Antmicro"
			(at 246.865 192.498 0)
			(layer "F.Fab")
			(hide yes)
			(effects
				(font
					(size 1 1)
					(thickness 0.15)
				)
			)
		)
		(property "Dielectric" ""
			(at 246.865 192.498 0)
			(layer "F.Fab")
			(hide yes)
			(effects
				(font
					(size 1 1)
					(thickness 0.15)
				)
			)
		)
		(property "License" "Apache-2.0"
			(at 246.865 192.498 0)
			(layer "F.Fab")
			(hide yes)
			(effects
				(font
					(size 1 1)
					(thickness 0.15)
				)
			)
		)
		(property "MPN" "04024W226MAT2A"
			(at 246.865 192.498 0)
			(layer "F.Fab")
			(hide yes)
			(effects
				(font
					(size 1 1)
					(thickness 0.15)
				)
			)
		)
		(property "Manufacturer" "AVX"
			(at 246.865 192.498 0)
			(layer "F.Fab")
			(hide yes)
			(effects
				(font
					(size 1 1)
					(thickness 0.15)
				)
			)
		)
		(property "Val" "22u"
			(at 246.865 192.498 0)
			(layer "F.Fab")
			(hide yes)
			(effects
				(font
					(size 1 1)
					(thickness 0.15)
				)
			)
		)
		(property "Voltage" ""
			(at 246.865 192.498 0)
			(layer "F.Fab")
			(hide yes)
			(effects
				(font
					(size 1 1)
					(thickness 0.15)
				)
			)
		)
		(sheetname "Supply")
		(sheetfile "supply.kicad_sch")
		(attr smd)
		(fp_rect
			(start -0.94 -0.47)
			(end 0.94 0.47)
			(stroke
				(width 0.05)
				(type solid)
			)
			(fill no)
			(layer "F.CrtYd")
		)
		(fp_rect
			(start -0.499 -0.249)
			(end 0.499 0.249)
			(stroke
				(width 0.15)
				(type solid)
			)
			(fill no)
			(layer "F.Fab")
		)
		(pad "1" smd roundrect
			(at -0.484 0 180)
			(size 0.59 0.64)
			(layers "F.Cu" "F.Mask" "F.Paste")
			(roundrect_rratio 0.25)
			(net 588 "/Supply/1V0_REG")
			(pintype "passive")
		)
		(pad "2" smd roundrect
			(at 0.484 0 180)
			(size 0.59 0.64)
			(layers "F.Cu" "F.Mask" "F.Paste")
			(roundrect_rratio 0.25)
			(net 5 "GND")
			(pintype "passive")
		)
	)
	(footprint "antmicro-footprints:R_0402_1005Metric"
		(layer "F.Cu")
		(at 118.275 99.549 180)
		(descr "Resistor SMD 0402")
		(tags "resistor SMD 0402")
		(property "Reference" "R119"
			(at 0.875 2.549 180)
			(layer "F.SilkS")
			(effects
				(font
					(size 0.7 0.7)
					(thickness 0.15)
				)
				(justify left bottom)
			)
		)
		(property "Value" "R_0R_0402"
			(at 0 1.4 180)
			(layer "F.Fab")
			(effects
				(font
					(size 0.7 0.7)
					(thickness 0.15)
				)
				(justify left bottom)
			)
		)
		(property "Description" "0R resistor in 0402 package with unspecified tolerance"
			(at 0 0 180)
			(layer "F.Fab")
			(hide yes)
			(effects
				(font
					(size 1.27 1.27)
					(thickness 0.15)
				)
			)
		)
		(property "Author" "Antmicro"
			(at 236.55 199.098 0)
			(layer "F.Fab")
			(hide yes)
			(effects
				(font
					(size 1 1)
					(thickness 0.15)
				)
			)
		)
		(property "Current" "1A"
			(at 236.55 199.098 0)
			(layer "F.Fab")
			(hide yes)
			(effects
				(font
					(size 1 1)
					(thickness 0.15)
				)
			)
		)
		(property "License" "Apache-2.0"
			(at 236.55 199.098 0)
			(layer "F.Fab")
			(hide yes)
			(effects
				(font
					(size 1 1)
					(thickness 0.15)
				)
			)
		)
		(property "MPN" "ERJ2GE0R00X"
			(at 236.55 199.098 0)
			(layer "F.Fab")
			(hide yes)
			(effects
				(font
					(size 1 1)
					(thickness 0.15)
				)
			)
		)
		(property "Manufacturer" "Panasonic"
			(at 236.55 199.098 0)
			(layer "F.Fab")
			(hide yes)
			(effects
				(font
					(size 1 1)
					(thickness 0.15)
				)
			)
		)
		(property "Tolerance" ""
			(at 236.55 199.098 0)
			(layer "F.Fab")
			(hide yes)
			(effects
				(font
					(size 1 1)
					(thickness 0.15)
				)
			)
		)
		(property "Val" "0R"
			(at 236.55 199.098 0)
			(layer "F.Fab")
			(hide yes)
			(effects
				(font
					(size 1 1)
					(thickness 0.15)
				)
			)
		)
		(sheetname "Supply")
		(sheetfile "supply.kicad_sch")
		(attr smd)
		(fp_rect
			(start -0.93 -0.47)
			(end 0.93 0.47)
			(stroke
				(width 0.05)
				(type solid)
			)
			(fill no)
			(layer "F.CrtYd")
		)
		(fp_rect
			(start -0.5 -0.25)
			(end 0.5 0.25)
			(stroke
				(width 0.15)
				(type solid)
			)
			(fill no)
			(layer "F.Fab")
		)
		(pad "1" smd roundrect
			(at -0.485 0 180)
			(size 0.59 0.64)
			(layers "F.Cu" "F.Mask" "F.Paste")
			(roundrect_rratio 0.25)
			(net 609 "/Supply/3V3_VCC_INT")
			(pintype "passive")
		)
		(pad "2" smd roundrect
			(at 0.485 0 180)
			(size 0.59 0.64)
			(layers "F.Cu" "F.Mask" "F.Paste")
			(roundrect_rratio 0.25)
			(net 610 "/Supply/3V3_FSEL")
			(pintype "passive")
		)
	)
	(footprint "antmicro-footprints:R_0402_1005Metric"
		(layer "F.Cu")
		(at 117.697806 88.074 180)
		(descr "Resistor SMD 0402")
		(tags "resistor SMD 0402")
		(property "Reference" "R120"
			(at 0.897806 3.574 180)
			(layer "F.SilkS")
			(effects
				(font
					(size 0.7 0.7)
					(thickness 0.15)
				)
				(justify left bottom)
			)
		)
		(property "Value" "R_0R_0402"
			(at 0 1.4 180)
			(layer "F.Fab")
			(effects
				(font
					(size 0.7 0.7)
					(thickness 0.15)
				)
				(justify left bottom)
			)
		)
		(property "Description" "0R resistor in 0402 package with unspecified tolerance"
			(at 0 0 180)
			(layer "F.Fab")
			(hide yes)
			(effects
				(font
					(size 1.27 1.27)
					(thickness 0.15)
				)
			)
		)
		(property "Author" "Antmicro"
			(at 235.395612 176.148 0)
			(layer "F.Fab")
			(hide yes)
			(effects
				(font
					(size 1 1)
					(thickness 0.15)
				)
			)
		)
		(property "Current" "1A"
			(at 235.395612 176.148 0)
			(layer "F.Fab")
			(hide yes)
			(effects
				(font
					(size 1 1)
					(thickness 0.15)
				)
			)
		)
		(property "License" "Apache-2.0"
			(at 235.395612 176.148 0)
			(layer "F.Fab")
			(hide yes)
			(effects
				(font
					(size 1 1)
					(thickness 0.15)
				)
			)
		)
		(property "MPN" "ERJ2GE0R00X"
			(at 235.395612 176.148 0)
			(layer "F.Fab")
			(hide yes)
			(effects
				(font
					(size 1 1)
					(thickness 0.15)
				)
			)
		)
		(property "Manufacturer" "Panasonic"
			(at 235.395612 176.148 0)
			(layer "F.Fab")
			(hide yes)
			(effects
				(font
					(size 1 1)
					(thickness 0.15)
				)
			)
		)
		(property "Tolerance" ""
			(at 235.395612 176.148 0)
			(layer "F.Fab")
			(hide yes)
			(effects
				(font
					(size 1 1)
					(thickness 0.15)
				)
			)
		)
		(property "Val" "0R"
			(at 235.395612 176.148 0)
			(layer "F.Fab")
			(hide yes)
			(effects
				(font
					(size 1 1)
					(thickness 0.15)
				)
			)
		)
		(sheetname "Supply")
		(sheetfile "supply.kicad_sch")
		(attr smd)
		(fp_rect
			(start -0.93 -0.47)
			(end 0.93 0.47)
			(stroke
				(width 0.05)
				(type solid)
			)
			(fill no)
			(layer "F.CrtYd")
		)
		(fp_rect
			(start -0.5 -0.25)
			(end 0.5 0.25)
			(stroke
				(width 0.15)
				(type solid)
			)
			(fill no)
			(layer "F.Fab")
		)
		(pad "1" smd roundrect
			(at -0.485 0 180)
			(size 0.59 0.64)
			(layers "F.Cu" "F.Mask" "F.Paste")
			(roundrect_rratio 0.25)
			(net 595 "/Supply/1V8_VCC_INT")
			(pintype "passive")
		)
		(pad "2" smd roundrect
			(at 0.485 0 180)
			(size 0.59 0.64)
			(layers "F.Cu" "F.Mask" "F.Paste")
			(roundrect_rratio 0.25)
			(net 614 "/Supply/1V8_FSEL")
			(pintype "passive")
		)
	)
	(footprint "antmicro-footprints:R_0402_1005Metric"
		(layer "F.Cu")
		(at 125.697157 53.213672)
		(descr "Resistor SMD 0402")
		(tags "resistor SMD 0402")
		(property "Reference" "R149"
			(at -1.197157 -1.613672 0)
			(layer "F.SilkS")
			(effects
				(font
					(size 0.7 0.7)
					(thickness 0.15)
				)
				(justify left bottom)
			)
		)
		(property "Value" "R_0R_0402"
			(at 0 1.4 0)
			(layer "F.Fab")
			(effects
				(font
					(size 0.7 0.7)
					(thickness 0.15)
				)
				(justify left bottom)
			)
		)
		(property "Description" "0R resistor in 0402 package with unspecified tolerance"
			(at 0 0 0)
			(layer "F.Fab")
			(hide yes)
			(effects
				(font
					(size 1.27 1.27)
					(thickness 0.15)
				)
			)
		)
		(property "Author" "Antmicro"
			(at 0 0 0)
			(layer "F.Fab")
			(hide yes)
			(effects
				(font
					(size 1 1)
					(thickness 0.15)
				)
			)
		)
		(property "Current" "1A"
			(at 0 0 0)
			(layer "F.Fab")
			(hide yes)
			(effects
				(font
					(size 1 1)
					(thickness 0.15)
				)
			)
		)
		(property "License" "Apache-2.0"
			(at 0 0 0)
			(layer "F.Fab")
			(hide yes)
			(effects
				(font
					(size 1 1)
					(thickness 0.15)
				)
			)
		)
		(property "MPN" "ERJ2GE0R00X"
			(at 0 0 0)
			(layer "F.Fab")
			(hide yes)
			(effects
				(font
					(size 1 1)
					(thickness 0.15)
				)
			)
		)
		(property "Manufacturer" "Panasonic"
			(at 0 0 0)
			(layer "F.Fab")
			(hide yes)
			(effects
				(font
					(size 1 1)
					(thickness 0.15)
				)
			)
		)
		(property "Tolerance" ""
			(at 0 0 0)
			(layer "F.Fab")
			(hide yes)
			(effects
				(font
					(size 1 1)
					(thickness 0.15)
				)
			)
		)
		(property "Val" "0R"
			(at 0 0 0)
			(layer "F.Fab")
			(hide yes)
			(effects
				(font
					(size 1 1)
					(thickness 0.15)
				)
			)
		)
		(sheetname "Supply")
		(sheetfile "supply.kicad_sch")
		(attr exclude_from_pos_files exclude_from_bom dnp)
		(fp_rect
			(start -0.93 -0.47)
			(end 0.93 0.47)
			(stroke
				(width 0.05)
				(type solid)
			)
			(fill no)
			(layer "F.CrtYd")
		)
		(fp_rect
			(start -0.5 -0.25)
			(end 0.5 0.25)
			(stroke
				(width 0.15)
				(type solid)
			)
			(fill no)
			(layer "F.Fab")
		)
		(pad "1" smd roundrect
			(at -0.485 0)
			(size 0.59 0.64)
			(layers "F.Cu" "F.Mask" "F.Paste")
			(roundrect_rratio 0.25)
			(net 631 "/Supply/VDDQ_SNS")
			(pintype "passive")
		)
		(pad "2" smd roundrect
			(at 0.485 0)
			(size 0.59 0.64)
			(layers "F.Cu" "F.Mask" "F.Paste")
			(roundrect_rratio 0.25)
			(net 627 "/Supply/VDDQ_0V6")
			(pintype "passive")
		)
	)
	(footprint "antmicro-footprints:R_0805_2012Metric"
		(layer "F.Cu")
		(at 131.6 50.6)
		(property "Reference" "R98"
			(at -1.1 -1 0)
			(layer "F.SilkS")
			(effects
				(font
					(size 0.7 0.7)
					(thickness 0.15)
				)
				(justify left bottom)
			)
		)
		(property "Value" "R_0R_0805"
			(at 0 1.8 0)
			(layer "F.Fab")
			(effects
				(font
					(size 0.7 0.7)
					(thickness 0.15)
				)
				(justify left bottom)
			)
		)
		(property "Description" "0R resistor in 0805 package with unspecified tolerance"
			(at 0 0 0)
			(layer "F.Fab")
			(hide yes)
			(effects
				(font
					(size 1.27 1.27)
					(thickness 0.15)
				)
			)
		)
		(property "Author" "Antmicro"
			(at 0 0 0)
			(layer "F.Fab")
			(hide yes)
			(effects
				(font
					(size 1 1)
					(thickness 0.15)
				)
			)
		)
		(property "Current" "2.5A"
			(at 0 0 0)
			(layer "F.Fab")
			(hide yes)
			(effects
				(font
					(size 1 1)
					(thickness 0.15)
				)
			)
		)
		(property "License" "Apache-2.0"
			(at 0 0 0)
			(layer "F.Fab")
			(hide yes)
			(effects
				(font
					(size 1 1)
					(thickness 0.15)
				)
			)
		)
		(property "MPN" "CRCW08050000Z0EA"
			(at 0 0 0)
			(layer "F.Fab")
			(hide yes)
			(effects
				(font
					(size 1 1)
					(thickness 0.15)
				)
			)
		)
		(property "Manufacturer" "Vishay"
			(at 0 0 0)
			(layer "F.Fab")
			(hide yes)
			(effects
				(font
					(size 1 1)
					(thickness 0.15)
				)
			)
		)
		(property "Tolerance" ""
			(at 0 0 0)
			(layer "F.Fab")
			(hide yes)
			(effects
				(font
					(size 1 1)
					(thickness 0.15)
				)
			)
		)
		(property "Val" "0R"
			(at 0 0 0)
			(layer "F.Fab")
			(hide yes)
			(effects
				(font
					(size 1 1)
					(thickness 0.15)
				)
			)
		)
		(sheetname "Supply")
		(sheetfile "supply.kicad_sch")
		(attr exclude_from_pos_files exclude_from_bom dnp)
		(fp_line
			(start -0.32 0.699)
			(end 0.28 0.699)
			(stroke
				(width 0.15)
				(type solid)
			)
			(layer "F.SilkS")
		)
		(fp_line
			(start -0.3 -0.701)
			(end 0.298 -0.701)
			(stroke
				(width 0.15)
				(type solid)
			)
			(layer "F.SilkS")
		)
		(fp_rect
			(start -1.75 -0.85)
			(end 1.75 0.85)
			(stroke
				(width 0.05)
				(type solid)
			)
			(fill no)
			(layer "F.CrtYd")
		)
		(fp_line
			(start -0.951 -0.682)
			(end 0.949 -0.682)
			(stroke
				(width 0.15)
				(type solid)
			)
			(layer "F.Fab")
		)
		(fp_line
			(start -0.951 -0.677)
			(end -0.951 0.675)
			(stroke
				(width 0.15)
				(type solid)
			)
			(layer "F.Fab")
		)
		(fp_line
			(start -0.951 0.68)
			(end 0.949 0.68)
			(stroke
				(width 0.15)
				(type solid)
			)
			(layer "F.Fab")
		)
		(fp_line
			(start 0.949 -0.677)
			(end 0.949 0.675)
			(stroke
				(width 0.15)
				(type solid)
			)
			(layer "F.Fab")
		)
		(pad "1" smd roundrect
			(at -1.1 -0.001)
			(size 1 1.4)
			(layers "F.Cu" "F.Mask" "F.Paste")
			(roundrect_rratio 0.15)
			(net 627 "/Supply/VDDQ_0V6")
			(pintype "passive")
		)
		(pad "2" smd roundrect
			(at 1.1 -0.001)
			(size 1 1.4)
			(layers "F.Cu" "F.Mask" "F.Paste")
			(roundrect_rratio 0.15)
			(net 640 "0V6_DDR")
			(pintype "passive")
		)
	)
)
